# T6G (Grand Teton) — schematic netlist excerpt (pin names and nets, part order shuffled) for the footprints in the layout excerpt that follows; sources: Cadence DE-HDL packaged netlist, KiCad conversion of 04192023_DAF0TMB3IC0_F0TG_MB_C_brd_V02_OCP.brd

PR3995  Q_RES  0 5% CHIP  pkg 0402LF  page 264 : A = HSC_FLT_TYPE_4 ; B = HSC_FLT_TYPE

U286  74LVC1G126SE7  74LVC1G126SE-7 IC  pkg SOT353_0-65_2X1-25  page 138
  OE  = OCP_V3_2_AUX_PWR_EN_R1
  A  = FM_OCP_V3_2_PWR_GOOD
  GND  = GND
  Y  = FB_BMC_ISOLATE_R2
  VCC  = P3V3_AUX

(kicad_pcb
	(version 20260206)
	(generator "pcbnew")
	(generator_version "10.0")
	(general
		(thickness 1.6)
		(legacy_teardrops no)
	)
	(paper "A4")
	(title_block
		(title "04192023_DAF0TMB3IC0_F0TG_MB_C_brd_V02_OCP.brd")
		(comment 1 "Grand Teton / footprints 4398-4399 of 8354")
	)
	(layers
		(0 "F.Cu" signal "TOP")
		(4 "In1.Cu" signal "GND")
		(6 "In2.Cu" signal "IN1")
		(8 "In3.Cu" signal "GND1")
		(10 "In4.Cu" signal "IN2")
		(12 "In5.Cu" signal "GND2")
		(14 "In6.Cu" signal "IN3")
		(16 "In7.Cu" signal "GND3")
		(18 "In8.Cu" signal "VCC")
		(20 "In9.Cu" signal "VCC1")
		(22 "In10.Cu" signal "GND4")
		(24 "In11.Cu" signal "IN4")
		(26 "In12.Cu" signal "GND5")
		(28 "In13.Cu" signal "IN5")
		(30 "In14.Cu" signal "GND6")
		(32 "In15.Cu" signal "IN6")
		(34 "In16.Cu" signal "GND7")
		(2 "B.Cu" signal "BOTTOM")
		(9 "F.Adhes" user "F.Adhesive")
		(11 "B.Adhes" user "B.Adhesive")
		(13 "F.Paste" user "Package Geometry/Pastemask Top")
		(15 "B.Paste" user "Package Geometry/Pastemask Bottom")
		(5 "F.SilkS" user "Ref Des/Silkscreen Top")
		(7 "B.SilkS" user "Ref Des/Silkscreen Bottom")
		(1 "F.Mask" user "Board Geometry/Soldermask Top")
		(3 "B.Mask" user "Board Geometry/Soldermask Bottom")
		(17 "Dwgs.User" user "User.Drawings")
		(19 "Cmts.User" user "User.Comments")
		(21 "Eco1.User" user "User.Eco1")
		(23 "Eco2.User" user "User.Eco2")
		(25 "Edge.Cuts" user "Board Geometry/Outline")
		(27 "Margin" user)
		(31 "F.CrtYd" user "Package Geometry/Place Bound Top")
		(29 "B.CrtYd" user "Package Geometry/Place Bound Bottom")
		(35 "F.Fab" user "Ref Des/Assembly Top")
		(33 "B.Fab" user "Ref Des/Assembly Bottom")
	)
	(footprint ""
		(layer "F.Cu")
		(at 49.12868 -29.657548 90)
		(property "Reference" "U286"
			(at -2.56286 -1.925828 90)
			(unlocked yes)
			(layer "F.SilkS")
			(effects
				(font
					(size 0.7874 0.5842)
					(thickness 0.1524)
				)
				(justify left)
			)
		)
		(property "Value" ""
			(at 0 0 90)
			(layer "F.Fab")
			(effects
				(font
					(size 1.27 1.27)
				)
			)
		)
		(duplicate_pad_numbers_are_jumpers no)
		(fp_line
			(start 1.400048 -1.100074)
			(end -1.400048 -1.100074)
			(stroke
				(width 0.1524)
				(type default)
			)
			(layer "F.SilkS")
		)
		(fp_line
			(start 1.400048 -1.100074)
			(end 1.400048 1.100074)
			(stroke
				(width 0.1524)
				(type default)
			)
			(layer "F.SilkS")
		)
		(fp_line
			(start 1.400048 1.100074)
			(end -1.400048 1.100074)
			(stroke
				(width 0.1524)
				(type default)
			)
			(layer "F.SilkS")
		)
		(fp_line
			(start -1.400048 1.100074)
			(end -1.400048 -1.100074)
			(stroke
				(width 0.1524)
				(type default)
			)
			(layer "F.SilkS")
		)
		(fp_poly
			(pts
				(xy -2.606548 -0.141986) (xy -2.606548 -1.157986) (xy -1.590548 -0.649986)
			)
			(stroke
				(width 0)
				(type default)
			)
			(fill yes)
			(layer "F.SilkS")
		)
		(fp_line
			(start 0.674878 -1.100074)
			(end 0.674878 1.100074)
			(stroke
				(width 0.1)
				(type default)
			)
			(layer "F.Fab")
		)
		(fp_line
			(start -0.674878 -1.100074)
			(end 0.674878 -1.100074)
			(stroke
				(width 0.1)
				(type default)
			)
			(layer "F.Fab")
		)
		(fp_line
			(start 0.674878 1.100074)
			(end -0.674878 1.100074)
			(stroke
				(width 0.1)
				(type default)
			)
			(layer "F.Fab")
		)
		(fp_line
			(start -0.674878 1.100074)
			(end -0.674878 -1.100074)
			(stroke
				(width 0.1)
				(type default)
			)
			(layer "F.Fab")
		)
		(fp_poly
			(pts
				(xy -1.590548 -0.649986) (xy -2.606548 -1.157986) (xy -2.606548 -0.141986)
			)
			(stroke
				(width 0)
				(type default)
			)
			(fill yes)
			(layer "F.Fab")
		)
		(pad "1" smd rect
			(at -0.94996 -0.649986)
			(size 0.4318 0.6096)
			(layers "F.Cu" "F.Mask" "F.Paste")
			(net "OCP_V3_2_AUX_PWR_EN_R1")
		)
		(pad "2" smd rect
			(at -0.94996 0)
			(size 0.4318 0.6096)
			(layers "F.Cu" "F.Mask" "F.Paste")
			(net "FM_OCP_V3_2_PWR_GOOD")
		)
		(pad "3" smd rect
			(at -0.94996 0.649986)
			(size 0.4318 0.6096)
			(layers "F.Cu" "F.Mask" "F.Paste")
			(net "GND")
		)
		(pad "4" smd rect
			(at 0.94996 0.649986)
			(size 0.4318 0.6096)
			(layers "F.Cu" "F.Mask" "F.Paste")
			(net "FB_BMC_ISOLATE_R2")
		)
		(pad "5" smd rect
			(at 0.94996 -0.649986)
			(size 0.4318 0.6096)
			(layers "F.Cu" "F.Mask" "F.Paste")
			(net "P3V3_AUX")
		)
	)
	(footprint ""
		(layer "F.Cu")
		(at 236.7661 -402.903182)
		(property "Reference" "PR3995"
			(at 0 0 0)
			(layer "F.SilkS")
			(hide yes)
			(effects
				(font
					(size 1.27 1.27)
				)
			)
		)
		(property "Value" ""
			(at 0 0 0)
			(layer "F.Fab")
			(effects
				(font
					(size 1.27 1.27)
				)
			)
		)
		(duplicate_pad_numbers_are_jumpers no)
		(fp_line
			(start -0.7874 -0.4064)
			(end 0.7874 -0.4064)
			(stroke
				(width 0.1524)
				(type default)
			)
			(layer "F.SilkS")
		)
		(fp_line
			(start -0.7874 0.4064)
			(end -0.7874 -0.4064)
			(stroke
				(width 0.1524)
				(type default)
			)
			(layer "F.SilkS")
		)
		(fp_line
			(start 0.7874 -0.4064)
			(end 0.7874 0.4064)
			(stroke
				(width 0.1524)
				(type default)
			)
			(layer "F.SilkS")
		)
		(fp_line
			(start 0.7874 0.4064)
			(end -0.7874 0.4064)
			(stroke
				(width 0.1524)
				(type default)
			)
			(layer "F.SilkS")
		)
		(fp_line
			(start -0.67945 -0.305054)
			(end -0.12065 -0.305054)
			(stroke
				(width 0.1)
				(type default)
			)
			(layer "F.Fab")
		)
		(fp_line
			(start -0.67945 0.3048)
			(end -0.67945 -0.305054)
			(stroke
				(width 0.1)
				(type default)
			)
			(layer "F.Fab")
		)
		(fp_line
			(start -0.12065 -0.305054)
			(end -0.12065 -0.2794)
			(stroke
				(width 0.1)
				(type default)
			)
			(layer "F.Fab")
		)
		(fp_line
			(start -0.12065 -0.2794)
			(end 0.12065 -0.2794)
			(stroke
				(width 0.1)
				(type default)
			)
			(layer "F.Fab")
		)
		(fp_line
			(start -0.12065 0.2794)
			(end -0.12065 0.3048)
			(stroke
				(width 0.1)
				(type default)
			)
			(layer "F.Fab")
		)
		(fp_line
			(start -0.12065 0.3048)
			(end -0.67945 0.3048)
			(stroke
				(width 0.1)
				(type default)
			)
			(layer "F.Fab")
		)
		(fp_line
			(start 0.120396 0.2794)
			(end -0.12065 0.2794)
			(stroke
				(width 0.1)
				(type default)
			)
			(layer "F.Fab")
		)
		(fp_line
			(start 0.120396 0.3048)
			(end 0.120396 0.2794)
			(stroke
				(width 0.1)
				(type default)
			)
			(layer "F.Fab")
		)
		(fp_line
			(start 0.12065 -0.3048)
			(end 0.67945 -0.3048)
			(stroke
				(width 0.1)
				(type default)
			)
			(layer "F.Fab")
		)
		(fp_line
			(start 0.12065 -0.2794)
			(end 0.12065 -0.3048)
			(stroke
				(width 0.1)
				(type default)
			)
			(layer "F.Fab")
		)
		(fp_line
			(start 0.67945 -0.3048)
			(end 0.67945 0.3048)
			(stroke
				(width 0.1)
				(type default)
			)
			(layer "F.Fab")
		)
		(fp_line
			(start 0.67945 0.3048)
			(end 0.120396 0.3048)
			(stroke
				(width 0.1)
				(type default)
			)
			(layer "F.Fab")
		)
		(pad "1" smd circle
			(at -0.40005 0)
			(size 0 0)
			(layers "F.Cu" "F.Mask" "F.Paste")
			(net "HSC_FLT_TYPE_4")
		)
		(pad "2" smd circle
			(at 0.40005 0)
			(size 0 0)
			(layers "F.Cu" "F.Mask" "F.Paste")
			(net "HSC_FLT_TYPE")
		)
	)
)
